(kicad_pcb
	(version 20241229)
	(generator "pcbnew")
	(generator_version "9.0")
	(general
		(thickness 1.294)
		(legacy_teardrops no)
	)
	(paper "A3")
	(title_block
		(title "Kintex 410T devboard")
		(date "2024-04-03")
		(rev "1.1.2")
		(comment 9 "footprints 225-226 of 975")
	)
	(layers
		(0 "F.Cu" mixed)
		(4 "In1.Cu" power)
		(6 "In2.Cu" power)
		(8 "In3.Cu" mixed)
		(10 "In4.Cu" power)
		(12 "In5.Cu" mixed)
		(14 "In6.Cu" power)
		(16 "In7.Cu" mixed)
		(18 "In8.Cu" power)
		(2 "B.Cu" mixed)
		(9 "F.Adhes" user "F.Adhesive")
		(11 "B.Adhes" user "B.Adhesive")
		(13 "F.Paste" user)
		(15 "B.Paste" user)
		(5 "F.SilkS" user "F.Silkscreen")
		(7 "B.SilkS" user "B.Silkscreen")
		(1 "F.Mask" user)
		(3 "B.Mask" user)
		(17 "Dwgs.User" user "User.Drawings")
		(19 "Cmts.User" user "User.Comments")
		(21 "Eco1.User" user "User.Eco1")
		(23 "Eco2.User" user "User.Eco2")
		(25 "Edge.Cuts" user)
		(27 "Margin" user)
		(31 "F.CrtYd" user "F.Courtyard")
		(29 "B.CrtYd" user "B.Courtyard")
		(35 "F.Fab" user)
		(33 "B.Fab" user)
	)
	(footprint "antmicro-footprints:NetTie-2_SMD_Pad0.127mm"
		(layer "F.Cu")
		(at 160.773 145.7)
		(descr "Net tie, 2 pin, 0.127mm  SMD pads")
		(tags "net tie")
		(property "Reference" "NT1"
			(at -0.128 -1.345 0)
			(layer "F.SilkS")
			(hide yes)
			(effects
				(font
					(size 0.7 0.7)
					(thickness 0.15)
				)
				(justify left bottom)
			)
		)
		(property "Value" "Net-Tie_2"
			(at 0 1.199 0)
			(layer "F.Fab")
			(effects
				(font
					(size 0.7 0.7)
					(thickness 0.15)
				)
				(justify left bottom)
			)
		)
		(property "Description" "Net tie, 2 pins"
			(at 0 0 0)
			(layer "F.Fab")
			(hide yes)
			(effects
				(font
					(size 1.27 1.27)
					(thickness 0.15)
				)
			)
		)
		(property "Author" "Antmicro"
			(at 0 0 0)
			(layer "F.Fab")
			(hide yes)
			(effects
				(font
					(size 1 1)
					(thickness 0.15)
				)
			)
		)
		(property "License" "Apache-2.0"
			(at 0 0 0)
			(layer "F.Fab")
			(hide yes)
			(effects
				(font
					(size 1 1)
					(thickness 0.15)
				)
			)
		)
		(property "MPN" ""
			(at 0 0 0)
			(layer "F.Fab")
			(hide yes)
			(effects
				(font
					(size 1 1)
					(thickness 0.15)
				)
			)
		)
		(property "Manufacturer" ""
			(at 0 0 0)
			(layer "F.Fab")
			(hide yes)
			(effects
				(font
					(size 1 1)
					(thickness 0.15)
				)
			)
		)
		(sheetname "DC-DC Converters")
		(sheetfile "dc-dc.kicad_sch")
		(attr exclude_from_pos_files)
		(net_tie_pad_groups "1, 2")
		(fp_poly
			(pts
				(xy -0.0635 -0.0635) (xy 0.0625 -0.0635) (xy 0.0625 0.0635) (xy -0.0635 0.0635)
			)
			(stroke
				(width 0)
				(type solid)
			)
			(fill yes)
			(layer "F.Cu")
		)
		(pad "1" smd roundrect
			(at -0.127 0 180)
			(size 0.127 0.127)
			(layers "F.Cu")
			(roundrect_rratio 0.5)
			(chamfer_ratio 0)
			(chamfer top_left bottom_left)
			(net 869 "Net-(NT1-Pad1)")
			(pinfunction "1")
			(pintype "passive")
		)
		(pad "2" smd roundrect
			(at 0.126 0)
			(size 0.127 0.127)
			(layers "F.Cu")
			(roundrect_rratio 0.5)
			(chamfer_ratio 0)
			(chamfer top_left bottom_left)
			(net 649 "VREFP")
			(pinfunction "2")
			(pintype "passive")
		)
	)
	(footprint "antmicro-footprints:Alliance_TFBGA-48"
		(layer "F.Cu")
		(at 221.75 130.65 180)
		(property "Reference" "U4"
			(at 0.7 4.2 180)
			(layer "F.SilkS")
			(effects
				(font
					(size 0.7 0.7)
					(thickness 0.15)
				)
				(justify left bottom)
			)
		)
		(property "Value" "AS6C8008-55BIN"
			(at -4.65 5.35 180)
			(layer "F.Fab")
			(effects
				(font
					(size 0.7 0.7)
					(thickness 0.15)
				)
				(justify left bottom)
			)
		)
		(property "Description" "SRAM, Asynchronous SRAM, 8 Mbit, TFBGA, 48 Pins, 2.7 V"
			(at 0 0 180)
			(layer "F.Fab")
			(hide yes)
			(effects
				(font
					(size 1.27 1.27)
					(thickness 0.15)
				)
			)
		)
		(property "Author" "Antmicro"
			(at 443.5 261.3 0)
			(layer "F.Fab")
			(hide yes)
			(effects
				(font
					(size 1 1)
					(thickness 0.15)
				)
			)
		)
		(property "License" "Apache-2.0"
			(at 443.5 261.3 0)
			(layer "F.Fab")
			(hide yes)
			(effects
				(font
					(size 1 1)
					(thickness 0.15)
				)
			)
		)
		(property "MPN" "AS6C8008-55BIN"
			(at 443.5 261.3 0)
			(layer "F.Fab")
			(hide yes)
			(effects
				(font
					(size 1 1)
					(thickness 0.15)
				)
			)
		)
		(property "Manufacturer" "Alliance Memory"
			(at 443.5 261.3 0)
			(layer "F.Fab")
			(hide yes)
			(effects
				(font
					(size 1 1)
					(thickness 0.15)
				)
			)
		)
		(sheetname "DRAM + SRAM")
		(sheetfile "ram.kicad_sch")
		(attr smd)
		(fp_line
			(start 2.999 3.999)
			(end 2.999 2.023)
			(stroke
				(width 0.15)
				(type solid)
			)
			(layer "F.SilkS")
		)
		(fp_line
			(start 2.999 3.999)
			(end 1.523 3.999)
			(stroke
				(width 0.15)
				(type solid)
			)
			(layer "F.SilkS")
		)
		(fp_line
			(start 2.999 -4)
			(end 2.999 -2.025)
			(stroke
				(width 0.15)
				(type solid)
			)
			(layer "F.SilkS")
		)
		(fp_line
			(start 2.999 -4)
			(end 1.523 -4)
			(stroke
				(width 0.15)
				(type solid)
			)
			(layer "F.SilkS")
		)
		(fp_line
			(start -3 3.999)
			(end -1.526 3.999)
			(stroke
				(width 0.15)
				(type solid)
			)
			(layer "F.SilkS")
		)
		(fp_line
			(start -3 3.999)
			(end -3 2.023)
			(stroke
				(width 0.15)
				(type solid)
			)
			(layer "F.SilkS")
		)
		(fp_line
			(start -3 -4)
			(end -1.526 -4)
			(stroke
				(width 0.15)
				(type solid)
			)
			(layer "F.SilkS")
		)
		(fp_line
			(start -3 -4)
			(end -3 -2.025)
			(stroke
				(width 0.15)
				(type solid)
			)
			(layer "F.SilkS")
		)
		(fp_circle
			(center -3.5 -2.63)
			(end -3.45 -2.63)
			(stroke
				(width 0.15)
				(type solid)
			)
			(fill yes)
			(layer "F.SilkS")
		)
		(fp_rect
			(start -3.5 -4.5)
			(end 3.499 4.499)
			(stroke
				(width 0.05)
				(type solid)
			)
			(fill no)
			(layer "F.CrtYd")
		)
		(fp_line
			(start 2.999 3.999)
			(end 2.999 -4)
			(stroke
				(width 0.15)
				(type solid)
			)
			(layer "F.Fab")
		)
		(fp_line
			(start 2.999 3.999)
			(end -3 3.999)
			(stroke
				(width 0.15)
				(type solid)
			)
			(layer "F.Fab")
		)
		(fp_line
			(start 2.999 -4)
			(end -3 -4)
			(stroke
				(width 0.15)
				(type solid)
			)
			(layer "F.Fab")
		)
		(fp_line
			(start -3 3.999)
			(end -3 -4)
			(stroke
				(width 0.15)
				(type solid)
			)
			(layer "F.Fab")
		)
		(fp_line
			(start -3 -3.8)
			(end -2.8 -4)
			(stroke
				(width 0.15)
				(type solid)
			)
			(layer "F.Fab")
		)
		(pad "A1" smd circle
			(at -1.875 -2.625 180)
			(size 0.33 0.33)
			(layers "F.Cu" "F.Mask" "F.Paste")
			(net 1122 "unconnected-(U4-NC-PadA1)")
			(pinfunction "NC")
			(pintype "no_connect")
		)
		(pad "A2" smd circle
			(at -1.125 -2.625 180)
			(size 0.33 0.33)
			(layers "F.Cu" "F.Mask" "F.Paste")
			(net 564 "/DRAM + SRAM/SRAM.~{OE}")
			(pinfunction "OE#")
			(pintype "input")
		)
		(pad "A3" smd circle
			(at -0.375 -2.625 180)
			(size 0.33 0.33)
			(layers "F.Cu" "F.Mask" "F.Paste")
			(net 680 "/DRAM + SRAM/SRAM.A0")
			(pinfunction "A0")
			(pintype "input")
		)
		(pad "A4" smd circle
			(at 0.372 -2.625 180)
			(size 0.33 0.33)
			(layers "F.Cu" "F.Mask" "F.Paste")
			(net 686 "/DRAM + SRAM/SRAM.A1")
			(pinfunction "A1")
			(pintype "input")
		)
		(pad "A5" smd circle
			(at 1.124 -2.625 180)
			(size 0.33 0.33)
			(layers "F.Cu" "F.Mask" "F.Paste")
			(net 671 "/DRAM + SRAM/SRAM.A2")
			(pinfunction "A2")
			(pintype "input")
		)
		(pad "A6" smd circle
			(at 1.874 -2.625 180)
			(size 0.33 0.33)
			(layers "F.Cu" "F.Mask" "F.Paste")
			(net 562 "/DRAM + SRAM/SRAM.CE2")
			(pinfunction "CE2")
			(pintype "input")
		)
		(pad "B1" smd circle
			(at -1.875 -1.875 180)
			(size 0.33 0.33)
			(layers "F.Cu" "F.Mask" "F.Paste")
			(net 1123 "unconnected-(U4-NC-PadB1)")
			(pinfunction "NC")
			(pintype "no_connect")
		)
		(pad "B2" smd circle
			(at -1.125 -1.875 180)
			(size 0.33 0.33)
			(layers "F.Cu" "F.Mask" "F.Paste")
			(net 1124 "unconnected-(U4-NC-PadB2)")
			(pinfunction "NC")
			(pintype "no_connect")
		)
		(pad "B3" smd circle
			(at -0.375 -1.875 180)
			(size 0.33 0.33)
			(layers "F.Cu" "F.Mask" "F.Paste")
			(net 672 "/DRAM + SRAM/SRAM.A3")
			(pinfunction "A3")
			(pintype "input")
		)
		(pad "B4" smd circle
			(at 0.372 -1.875 180)
			(size 0.33 0.33)
			(layers "F.Cu" "F.Mask" "F.Paste")
			(net 682 "/DRAM + SRAM/SRAM.A4")
			(pinfunction "A4")
			(pintype "input")
		)
		(pad "B5" smd circle
			(at 1.124 -1.875 180)
			(size 0.33 0.33)
			(layers "F.Cu" "F.Mask" "F.Paste")
			(net 556 "/DRAM + SRAM/SRAM.~{CE}")
			(pinfunction "CE#")
			(pintype "input")
		)
		(pad "B6" smd circle
			(at 1.874 -1.875 180)
			(size 0.33 0.33)
			(layers "F.Cu" "F.Mask" "F.Paste")
			(net 1125 "unconnected-(U4-NC-PadB6)")
			(pinfunction "NC")
			(pintype "no_connect")
		)
		(pad "C1" smd circle
			(at -1.875 -1.125 180)
			(size 0.33 0.33)
			(layers "F.Cu" "F.Mask" "F.Paste")
			(net 683 "/DRAM + SRAM/SRAM.DQ0")
			(pinfunction "DQ0")
			(pintype "bidirectional")
		)
		(pad "C2" smd circle
			(at -1.125 -1.125 180)
			(size 0.33 0.33)
			(layers "F.Cu" "F.Mask" "F.Paste")
			(net 1126 "unconnected-(U4-NC-PadC2)")
			(pinfunction "NC")
			(pintype "no_connect")
		)
		(pad "C3" smd circle
			(at -0.375 -1.125 180)
			(size 0.33 0.33)
			(layers "F.Cu" "F.Mask" "F.Paste")
			(net 664 "/DRAM + SRAM/SRAM.A5")
			(pinfunction "A5")
			(pintype "input")
		)
		(pad "C4" smd circle
			(at 0.372 -1.125 180)
			(size 0.33 0.33)
			(layers "F.Cu" "F.Mask" "F.Paste")
			(net 665 "/DRAM + SRAM/SRAM.A6")
			(pinfunction "A6")
			(pintype "input")
		)
		(pad "C5" smd circle
			(at 1.124 -1.125 180)
			(size 0.33 0.33)
			(layers "F.Cu" "F.Mask" "F.Paste")
			(net 1127 "unconnected-(U4-NC-PadC5)")
			(pinfunction "NC")
			(pintype "no_connect")
		)
		(pad "C6" smd circle
			(at 1.874 -1.125 180)
			(size 0.33 0.33)
			(layers "F.Cu" "F.Mask" "F.Paste")
			(net 676 "/DRAM + SRAM/SRAM.DQ4")
			(pinfunction "DQ4")
			(pintype "bidirectional")
		)
		(pad "D1" smd circle
			(at -1.875 -0.375 180)
			(size 0.33 0.33)
			(layers "F.Cu" "F.Mask" "F.Paste")
			(net 1 "GND")
			(pinfunction "VSS")
			(pintype "passive")
		)
		(pad "D2" smd circle
			(at -1.125 -0.375 180)
			(size 0.33 0.33)
			(layers "F.Cu" "F.Mask" "F.Paste")
			(net 687 "/DRAM + SRAM/SRAM.DQ1")
			(pinfunction "DQ1")
			(pintype "bidirectional")
		)
		(pad "D3" smd circle
			(at -0.375 -0.375 180)
			(size 0.33 0.33)
			(layers "F.Cu" "F.Mask" "F.Paste")
			(net 690 "/DRAM + SRAM/SRAM.A17")
			(pinfunction "A17")
			(pintype "input")
		)
		(pad "D4" smd circle
			(at 0.372 -0.375 180)
			(size 0.33 0.33)
			(layers "F.Cu" "F.Mask" "F.Paste")
			(net 684 "/DRAM + SRAM/SRAM.A7")
			(pinfunction "A7")
			(pintype "input")
		)
		(pad "D5" smd circle
			(at 1.124 -0.375 180)
			(size 0.33 0.33)
			(layers "F.Cu" "F.Mask" "F.Paste")
			(net 674 "/DRAM + SRAM/SRAM.DQ5")
			(pinfunction "DQ5")
			(pintype "bidirectional")
		)
		(pad "D6" smd circle
			(at 1.874 -0.375 180)
			(size 0.33 0.33)
			(layers "F.Cu" "F.Mask" "F.Paste")
			(net 24 "+3V3")
			(pinfunction "VCC")
			(pintype "power_in")
		)
		(pad "E1" smd circle
			(at -1.875 0.372 180)
			(size 0.33 0.33)
			(layers "F.Cu" "F.Mask" "F.Paste")
			(net 24 "+3V3")
			(pinfunction "VCC")
			(pintype "passive")
		)
		(pad "E2" smd circle
			(at -1.125 0.372 180)
			(size 0.33 0.33)
			(layers "F.Cu" "F.Mask" "F.Paste")
			(net 688 "/DRAM + SRAM/SRAM.DQ2")
			(pinfunction "DQ2")
			(pintype "bidirectional")
		)
		(pad "E3" smd circle
			(at -0.375 0.372 180)
			(size 0.33 0.33)
			(layers "F.Cu" "F.Mask" "F.Paste")
			(net 1128 "unconnected-(U4-NC-PadE3)")
			(pinfunction "NC")
			(pintype "no_connect")
		)
		(pad "E4" smd circle
			(at 0.372 0.372 180)
			(size 0.33 0.33)
			(layers "F.Cu" "F.Mask" "F.Paste")
			(net 689 "/DRAM + SRAM/SRAM.A16")
			(pinfunction "A16")
			(pintype "input")
		)
		(pad "E5" smd circle
			(at 1.124 0.372 180)
			(size 0.33 0.33)
			(layers "F.Cu" "F.Mask" "F.Paste")
			(net 668 "/DRAM + SRAM/SRAM.DQ6")
			(pinfunction "DQ6")
			(pintype "bidirectional")
		)
		(pad "E6" smd circle
			(at 1.874 0.372 180)
			(size 0.33 0.33)
			(layers "F.Cu" "F.Mask" "F.Paste")
			(net 1 "GND")
			(pinfunction "VSS")
			(pintype "passive")
		)
		(pad "F1" smd circle
			(at -1.875 1.124 180)
			(size 0.33 0.33)
			(layers "F.Cu" "F.Mask" "F.Paste")
			(net 666 "/DRAM + SRAM/SRAM.DQ3")
			(pinfunction "DQ3")
			(pintype "bidirectional")
		)
		(pad "F2" smd circle
			(at -1.125 1.124 180)
			(size 0.33 0.33)
			(layers "F.Cu" "F.Mask" "F.Paste")
			(net 1129 "unconnected-(U4-NC-PadF2)")
			(pinfunction "NC")
			(pintype "no_connect")
		)
		(pad "F3" smd circle
			(at -0.375 1.124 180)
			(size 0.33 0.33)
			(layers "F.Cu" "F.Mask" "F.Paste")
			(net 677 "/DRAM + SRAM/SRAM.A14")
			(pinfunction "A14")
			(pintype "input")
		)
		(pad "F4" smd circle
			(at 0.372 1.124 180)
			(size 0.33 0.33)
			(layers "F.Cu" "F.Mask" "F.Paste")
			(net 675 "/DRAM + SRAM/SRAM.A15")
			(pinfunction "A15")
			(pintype "input")
		)
		(pad "F5" smd circle
			(at 1.124 1.124 180)
			(size 0.33 0.33)
			(layers "F.Cu" "F.Mask" "F.Paste")
			(net 1130 "unconnected-(U4-NC-PadF5)")
			(pinfunction "NC")
			(pintype "no_connect")
		)
		(pad "F6" smd circle
			(at 1.874 1.124 180)
			(size 0.33 0.33)
			(layers "F.Cu" "F.Mask" "F.Paste")
			(net 669 "/DRAM + SRAM/SRAM.DQ7")
			(pinfunction "DQ7")
			(pintype "bidirectional")
		)
		(pad "G1" smd circle
			(at -1.875 1.874 180)
			(size 0.33 0.33)
			(layers "F.Cu" "F.Mask" "F.Paste")
			(net 1131 "unconnected-(U4-NC-PadG1)")
			(pinfunction "NC")
			(pintype "no_connect")
		)
		(pad "G2" smd circle
			(at -1.125 1.874 180)
			(size 0.33 0.33)
			(layers "F.Cu" "F.Mask" "F.Paste")
			(net 1132 "unconnected-(U4-NC-PadG2)")
			(pinfunction "NC")
			(pintype "no_connect")
		)
		(pad "G3" smd circle
			(at -0.375 1.874 180)
			(size 0.33 0.33)
			(layers "F.Cu" "F.Mask" "F.Paste")
			(net 681 "/DRAM + SRAM/SRAM.A12")
			(pinfunction "A12")
			(pintype "input")
		)
		(pad "G4" smd circle
			(at 0.372 1.874 180)
			(size 0.33 0.33)
			(layers "F.Cu" "F.Mask" "F.Paste")
			(net 673 "/DRAM + SRAM/SRAM.A13")
			(pinfunction "A13")
			(pintype "input")
		)
		(pad "G5" smd circle
			(at 1.124 1.874 180)
			(size 0.33 0.33)
			(layers "F.Cu" "F.Mask" "F.Paste")
			(net 563 "/DRAM + SRAM/SRAM.~{WE}")
			(pinfunction "WE#")
			(pintype "input")
		)
		(pad "G6" smd circle
			(at 1.874 1.874 180)
			(size 0.33 0.33)
			(layers "F.Cu" "F.Mask" "F.Paste")
			(net 1133 "unconnected-(U4-NC-PadG6)")
			(pinfunction "NC")
			(pintype "no_connect")
		)
		(pad "H1" smd circle
			(at -1.875 2.624 180)
			(size 0.33 0.33)
			(layers "F.Cu" "F.Mask" "F.Paste")
			(net 685 "/DRAM + SRAM/SRAM.A18")
			(pinfunction "A18")
			(pintype "input")
		)
		(pad "H2" smd circle
			(at -1.125 2.624 180)
			(size 0.33 0.33)
			(layers "F.Cu" "F.Mask" "F.Paste")
			(net 667 "/DRAM + SRAM/SRAM.A8")
			(pinfunction "A8")
			(pintype "input")
		)
		(pad "H3" smd circle
			(at -0.375 2.624 180)
			(size 0.33 0.33)
			(layers "F.Cu" "F.Mask" "F.Paste")
			(net 670 "/DRAM + SRAM/SRAM.A9")
			(pinfunction "A9")
			(pintype "input")
		)
		(pad "H4" smd circle
			(at 0.372 2.624 180)
			(size 0.33 0.33)
			(layers "F.Cu" "F.Mask" "F.Paste")
			(net 679 "/DRAM + SRAM/SRAM.A10")
			(pinfunction "A10")
			(pintype "input")
		)
		(pad "H5" smd circle
			(at 1.124 2.624 180)
			(size 0.33 0.33)
			(layers "F.Cu" "F.Mask" "F.Paste")
			(net 678 "/DRAM + SRAM/SRAM.A11")
			(pinfunction "A11")
			(pintype "input")
		)
		(pad "H6" smd circle
			(at 1.874 2.624 180)
			(size 0.33 0.33)
			(layers "F.Cu" "F.Mask" "F.Paste")
			(net 691 "/DRAM + SRAM/SRAM.A19")
			(pinfunction "A19")
			(pintype "input")
		)
	)
)
